(kicad_pcb
	(version 20260206)
	(generator "pcbnew")
	(generator_version "10.0")
	(general
		(thickness 1.6)
		(legacy_teardrops no)
	)
	(paper "A4")
	(title_block
		(title "pdpb — Lightning_PDPB_BRD.brd")
		(comment 1 "Lightning (Wiwynn / Facebook NVMe JBOF) / footprints 303-309 of 1140")
	)
	(layers
		(0 "F.Cu" signal "TOP")
		(4 "In1.Cu" signal "L2GND")
		(6 "In2.Cu" signal "L3")
		(8 "In3.Cu" signal "L4VCC")
		(10 "In4.Cu" signal "L5VCC")
		(12 "In5.Cu" signal "L6")
		(14 "In6.Cu" signal "L7GND")
		(2 "B.Cu" signal "BOTTOM")
		(9 "F.Adhes" user "F.Adhesive")
		(11 "B.Adhes" user "B.Adhesive")
		(13 "F.Paste" user "Package Geometry/Pastemask Top")
		(15 "B.Paste" user "Package Geometry/Pastemask Bottom")
		(5 "F.SilkS" user "Ref Des/Silkscreen Top")
		(7 "B.SilkS" user "Ref Des/Silkscreen Bottom")
		(1 "F.Mask" user "Board Geometry/Soldermask Top")
		(3 "B.Mask" user "Board Geometry/Soldermask Bottom")
		(17 "Dwgs.User" user "User.Drawings")
		(19 "Cmts.User" user "User.Comments")
		(21 "Eco1.User" user "User.Eco1")
		(23 "Eco2.User" user "User.Eco2")
		(25 "Edge.Cuts" user "Board Geometry/Outline")
		(27 "Margin" user)
		(31 "F.CrtYd" user "Package Geometry/Place Bound Top")
		(29 "B.CrtYd" user "Package Geometry/Place Bound Bottom")
		(35 "F.Fab" user "Ref Des/Assembly Top")
		(33 "B.Fab" user "Ref Des/Assembly Bottom")
	)
	(footprint ""
		(layer "F.Cu")
		(at 15.494 -491.363)
		(property "Reference" "R556"
			(at 0 0 0)
			(layer "F.SilkS")
			(hide yes)
			(effects
				(font
					(size 1.27 1.27)
				)
			)
		)
		(property "Value" "200KR2F-L-GP"
			(at 0.064008 -3.993896 0)
			(unlocked yes)
			(layer "F.Fab")
			(hide yes)
			(effects
				(font
					(size 1.016 1.016)
					(thickness 0.1524)
				)
			)
		)
		(property "Device Type" "R402H16"
			(at 0.064008 -5.517896 0)
			(unlocked yes)
			(layer "F.Fab")
			(hide yes)
			(effects
				(font
					(size 1.016 1.016)
					(thickness 0.1524)
				)
			)
		)
		(duplicate_pad_numbers_are_jumpers no)
		(fp_line
			(start -0.508 -0.9398)
			(end -0.508 0.9398)
			(stroke
				(width 0.1524)
				(type default)
			)
			(layer "F.SilkS")
		)
		(fp_line
			(start 0.508 -0.9398)
			(end -0.508 -0.9398)
			(stroke
				(width 0.1524)
				(type default)
			)
			(layer "F.SilkS")
		)
		(fp_rect
			(start -0.508 0.9398)
			(end 0.508 -0.9398)
			(stroke
				(width 0)
				(type default)
			)
			(fill no)
			(layer "F.CrtYd")
		)
		(fp_rect
			(start -0.508 0.9398)
			(end 0.508 -0.9398)
			(stroke
				(width 0)
				(type default)
			)
			(fill no)
			(layer "F.Fab")
		)
		(pad "1" smd custom
			(at 0 -0.4445)
			(size 0.1397 0.1397)
			(layers "F.Cu" "F.Mask" "F.Paste")
			(net "SW_SSD5_R")
			(options
				(clearance outline)
				(anchor circle)
			)
			(primitives
				(gr_poly
					(pts
						(arc
							(start -0.1778 -0.2794)
							(mid -0.249642 -0.249642)
							(end -0.2794 -0.1778)
						)
						(arc
							(start -0.2794 0.1778)
							(mid -0.249642 0.249642)
							(end -0.1778 0.2794)
						)
						(arc
							(start 0.1778 0.2794)
							(mid 0.249642 0.249642)
							(end 0.2794 0.1778)
						)
						(arc
							(start 0.2794 -0.1778)
							(mid 0.249642 -0.249642)
							(end 0.1778 -0.2794)
						)
					)
					(width 0)
					(fill yes)
				)
			)
		)
		(pad "2" smd custom
			(at 0 0.4445)
			(size 0.1397 0.1397)
			(layers "F.Cu" "F.Mask" "F.Paste")
			(net "SW_SSD5_N")
			(options
				(clearance outline)
				(anchor circle)
			)
			(primitives
				(gr_poly
					(pts
						(arc
							(start -0.1778 -0.2794)
							(mid -0.249642 -0.249642)
							(end -0.2794 -0.1778)
						)
						(arc
							(start -0.2794 0.1778)
							(mid -0.249642 0.249642)
							(end -0.1778 0.2794)
						)
						(arc
							(start 0.1778 0.2794)
							(mid 0.249642 0.249642)
							(end 0.2794 0.1778)
						)
						(arc
							(start 0.2794 -0.1778)
							(mid 0.249642 -0.249642)
							(end 0.1778 -0.2794)
						)
					)
					(width 0)
					(fill yes)
				)
			)
		)
	)
	(footprint ""
		(layer "F.Cu")
		(at 82.931 -104.902 -90)
		(property "Reference" "PR9064"
			(at 0 0 270)
			(layer "F.SilkS")
			(hide yes)
			(effects
				(font
					(size 1.27 1.27)
				)
			)
		)
		(property "Value" "1K4R2F-1-GP"
			(at 0.064008 -3.993896 270)
			(unlocked yes)
			(layer "F.Fab")
			(hide yes)
			(effects
				(font
					(size 1.016 1.016)
					(thickness 0.1524)
				)
			)
		)
		(property "Device Type" "R402H16"
			(at 0.064008 -5.517896 270)
			(unlocked yes)
			(layer "F.Fab")
			(hide yes)
			(effects
				(font
					(size 1.016 1.016)
					(thickness 0.1524)
				)
			)
		)
		(duplicate_pad_numbers_are_jumpers no)
		(fp_line
			(start -0.508 -0.9398)
			(end -0.508 0.9398)
			(stroke
				(width 0.1524)
				(type default)
			)
			(layer "F.SilkS")
		)
		(fp_line
			(start 0.508 -0.9398)
			(end -0.508 -0.9398)
			(stroke
				(width 0.1524)
				(type default)
			)
			(layer "F.SilkS")
		)
		(fp_rect
			(start -0.508 0.9398)
			(end 0.508 -0.9398)
			(stroke
				(width 0)
				(type default)
			)
			(fill no)
			(layer "F.CrtYd")
		)
		(fp_rect
			(start -0.508 0.9398)
			(end 0.508 -0.9398)
			(stroke
				(width 0)
				(type default)
			)
			(fill no)
			(layer "F.Fab")
		)
		(pad "1" smd custom
			(at 0 -0.4445 270)
			(size 0.1397 0.1397)
			(layers "F.Cu" "F.Mask" "F.Paste")
			(net "CLK_BUF_EU4_HIBW_BYPM_LOBW#")
			(options
				(clearance outline)
				(anchor circle)
			)
			(primitives
				(gr_poly
					(pts
						(arc
							(start -0.1778 -0.2794)
							(mid -0.249642 -0.249642)
							(end -0.2794 -0.1778)
						)
						(arc
							(start -0.2794 0.1778)
							(mid -0.249642 0.249642)
							(end -0.1778 0.2794)
						)
						(arc
							(start 0.1778 0.2794)
							(mid 0.249642 0.249642)
							(end 0.2794 0.1778)
						)
						(arc
							(start 0.2794 -0.1778)
							(mid 0.249642 -0.249642)
							(end 0.1778 -0.2794)
						)
					)
					(width 0)
					(fill yes)
				)
			)
		)
		(pad "2" smd custom
			(at 0 0.4445 270)
			(size 0.1397 0.1397)
			(layers "F.Cu" "F.Mask" "F.Paste")
			(net "GND")
			(options
				(clearance outline)
				(anchor circle)
			)
			(primitives
				(gr_poly
					(pts
						(arc
							(start -0.1778 -0.2794)
							(mid -0.249642 -0.249642)
							(end -0.2794 -0.1778)
						)
						(arc
							(start -0.2794 0.1778)
							(mid -0.249642 0.249642)
							(end -0.1778 0.2794)
						)
						(arc
							(start 0.1778 0.2794)
							(mid 0.249642 0.249642)
							(end 0.2794 0.1778)
						)
						(arc
							(start 0.2794 -0.1778)
							(mid 0.249642 -0.249642)
							(end 0.1778 -0.2794)
						)
					)
					(width 0)
					(fill yes)
				)
			)
		)
	)
	(footprint ""
		(layer "F.Cu")
		(at 233.807 -344.801952 180)
		(property "Reference" "Q33"
			(at 0 0 180)
			(layer "F.SilkS")
			(hide yes)
			(effects
				(font
					(size 1.27 1.27)
				)
			)
		)
		(property "Value" "2N7002A-7-GP"
			(at 0.127 -8.9662 180)
			(unlocked yes)
			(layer "F.Fab")
			(hide yes)
			(effects
				(font
					(size 1.016 1.016)
					(thickness 0.1524)
				)
			)
		)
		(property "Device Type" "SOT23DGS2D4H48"
			(at 0.127 -10.4902 180)
			(unlocked yes)
			(layer "F.Fab")
			(hide yes)
			(effects
				(font
					(size 1.016 1.016)
					(thickness 0.1524)
				)
			)
		)
		(duplicate_pad_numbers_are_jumpers no)
		(fp_line
			(start 1.651 1.778)
			(end 1.651 -1.778)
			(stroke
				(width 0.1524)
				(type default)
			)
			(layer "F.SilkS")
		)
		(fp_line
			(start 1.651 -1.778)
			(end -1.651 -1.778)
			(stroke
				(width 0.1524)
				(type default)
			)
			(layer "F.SilkS")
		)
		(fp_line
			(start -1.651 1.778)
			(end 1.651 1.778)
			(stroke
				(width 0.1524)
				(type default)
			)
			(layer "F.SilkS")
		)
		(fp_line
			(start -1.651 -1.778)
			(end -1.651 1.778)
			(stroke
				(width 0.1524)
				(type default)
			)
			(layer "F.SilkS")
		)
		(fp_poly
			(pts
				(xy -1.778 1.8796) (xy -1.778 -1.8796) (xy 1.778 -1.8796) (xy 1.778 1.8796)
			)
			(stroke
				(width 0)
				(type default)
			)
			(fill no)
			(layer "F.CrtYd")
		)
		(fp_poly
			(pts
				(xy -1.778 1.8796) (xy -1.778 -1.8796) (xy 1.778 -1.8796) (xy 1.778 1.8796)
			)
			(stroke
				(width 0)
				(type default)
			)
			(fill no)
			(layer "F.Fab")
		)
		(pad "D" smd custom
			(at 0 -0.9525 180)
			(size 0.1905 0.1905)
			(layers "F.Cu" "F.Mask" "F.Paste")
			(net "SSD_ACT_DR1_MOS_N")
			(options
				(clearance outline)
				(anchor circle)
			)
			(primitives
				(gr_poly
					(pts
						(arc
							(start -0.1778 0.5715)
							(mid -0.321484 0.511984)
							(end -0.381 0.3683)
						)
						(arc
							(start -0.381 -0.3683)
							(mid -0.321484 -0.511984)
							(end -0.1778 -0.5715)
						)
						(arc
							(start 0.1778 -0.5715)
							(mid 0.321484 -0.511984)
							(end 0.381 -0.3683)
						)
						(arc
							(start 0.381 0.3683)
							(mid 0.321484 0.511984)
							(end 0.1778 0.5715)
						)
					)
					(width 0)
					(fill yes)
				)
			)
		)
		(pad "G" smd custom
			(at -0.98425 0.9525 180)
			(size 0.1905 0.1905)
			(layers "F.Cu" "F.Mask" "F.Paste")
			(net "ATTN_LED_DR1_AND_R")
			(options
				(clearance outline)
				(anchor circle)
			)
			(primitives
				(gr_poly
					(pts
						(arc
							(start -0.1778 0.5715)
							(mid -0.321484 0.511984)
							(end -0.381 0.3683)
						)
						(arc
							(start -0.381 -0.3683)
							(mid -0.321484 -0.511984)
							(end -0.1778 -0.5715)
						)
						(arc
							(start 0.1778 -0.5715)
							(mid 0.321484 -0.511984)
							(end 0.381 -0.3683)
						)
						(arc
							(start 0.381 0.3683)
							(mid 0.321484 0.511984)
							(end 0.1778 0.5715)
						)
					)
					(width 0)
					(fill yes)
				)
			)
		)
		(pad "S" smd custom
			(at 0.98425 0.9525 180)
			(size 0.1905 0.1905)
			(layers "F.Cu" "F.Mask" "F.Paste")
			(net "SSD_ACT_DR1_R")
			(options
				(clearance outline)
				(anchor circle)
			)
			(primitives
				(gr_poly
					(pts
						(arc
							(start -0.1778 0.5715)
							(mid -0.321484 0.511984)
							(end -0.381 0.3683)
						)
						(arc
							(start -0.381 -0.3683)
							(mid -0.321484 -0.511984)
							(end -0.1778 -0.5715)
						)
						(arc
							(start 0.1778 -0.5715)
							(mid 0.321484 -0.511984)
							(end 0.381 -0.3683)
						)
						(arc
							(start 0.381 0.3683)
							(mid 0.321484 0.511984)
							(end 0.1778 0.5715)
						)
					)
					(width 0)
					(fill yes)
				)
			)
		)
	)
	(footprint ""
		(layer "F.Cu")
		(at 96.0374 -21.9456)
		(property "Reference" "R390"
			(at 0 0 0)
			(layer "F.SilkS")
			(hide yes)
			(effects
				(font
					(size 1.27 1.27)
				)
			)
		)
		(property "Value" "2KR2F-3-GP"
			(at 0.064008 -3.993896 0)
			(unlocked yes)
			(layer "F.Fab")
			(hide yes)
			(effects
				(font
					(size 1.016 1.016)
					(thickness 0.1524)
				)
			)
		)
		(property "Device Type" "R402H16"
			(at 0.064008 -5.517896 0)
			(unlocked yes)
			(layer "F.Fab")
			(hide yes)
			(effects
				(font
					(size 1.016 1.016)
					(thickness 0.1524)
				)
			)
		)
		(duplicate_pad_numbers_are_jumpers no)
		(fp_line
			(start -0.508 -0.9398)
			(end -0.508 0.9398)
			(stroke
				(width 0.1524)
				(type default)
			)
			(layer "F.SilkS")
		)
		(fp_line
			(start 0.508 -0.9398)
			(end -0.508 -0.9398)
			(stroke
				(width 0.1524)
				(type default)
			)
			(layer "F.SilkS")
		)
		(fp_rect
			(start -0.508 0.9398)
			(end 0.508 -0.9398)
			(stroke
				(width 0)
				(type default)
			)
			(fill no)
			(layer "F.CrtYd")
		)
		(fp_rect
			(start -0.508 0.9398)
			(end 0.508 -0.9398)
			(stroke
				(width 0)
				(type default)
			)
			(fill no)
			(layer "F.Fab")
		)
		(pad "1" smd custom
			(at 0 -0.4445)
			(size 0.1397 0.1397)
			(layers "F.Cu" "F.Mask" "F.Paste")
			(net "P12V_SSD14_SENSE")
			(options
				(clearance outline)
				(anchor circle)
			)
			(primitives
				(gr_poly
					(pts
						(arc
							(start -0.1778 -0.2794)
							(mid -0.249642 -0.249642)
							(end -0.2794 -0.1778)
						)
						(arc
							(start -0.2794 0.1778)
							(mid -0.249642 0.249642)
							(end -0.1778 0.2794)
						)
						(arc
							(start 0.1778 0.2794)
							(mid 0.249642 0.249642)
							(end 0.2794 0.1778)
						)
						(arc
							(start 0.2794 -0.1778)
							(mid 0.249642 -0.249642)
							(end 0.1778 -0.2794)
						)
					)
					(width 0)
					(fill yes)
				)
			)
		)
		(pad "2" smd custom
			(at 0 0.4445)
			(size 0.1397 0.1397)
			(layers "F.Cu" "F.Mask" "F.Paste")
			(net "GND")
			(options
				(clearance outline)
				(anchor circle)
			)
			(primitives
				(gr_poly
					(pts
						(arc
							(start -0.1778 -0.2794)
							(mid -0.249642 -0.249642)
							(end -0.2794 -0.1778)
						)
						(arc
							(start -0.2794 0.1778)
							(mid -0.249642 0.249642)
							(end -0.1778 0.2794)
						)
						(arc
							(start 0.1778 0.2794)
							(mid 0.249642 0.249642)
							(end 0.2794 0.1778)
						)
						(arc
							(start 0.2794 -0.1778)
							(mid 0.249642 -0.249642)
							(end 0.1778 -0.2794)
						)
					)
					(width 0)
					(fill yes)
				)
			)
		)
	)
	(footprint ""
		(layer "F.Cu")
		(at 97.409 -195.834 -90)
		(property "Reference" "R9496"
			(at 0 0 270)
			(layer "F.SilkS")
			(hide yes)
			(effects
				(font
					(size 1.27 1.27)
				)
			)
		)
		(property "Value" "4K7R2J-2-GP"
			(at 0.064008 -3.993896 270)
			(unlocked yes)
			(layer "F.Fab")
			(hide yes)
			(effects
				(font
					(size 1.016 1.016)
					(thickness 0.1524)
				)
			)
		)
		(property "Device Type" "R402H16"
			(at 0.064008 -5.517896 270)
			(unlocked yes)
			(layer "F.Fab")
			(hide yes)
			(effects
				(font
					(size 1.016 1.016)
					(thickness 0.1524)
				)
			)
		)
		(duplicate_pad_numbers_are_jumpers no)
		(fp_line
			(start -0.508 -0.9398)
			(end -0.508 0.9398)
			(stroke
				(width 0.1524)
				(type default)
			)
			(layer "F.SilkS")
		)
		(fp_line
			(start 0.508 -0.9398)
			(end -0.508 -0.9398)
			(stroke
				(width 0.1524)
				(type default)
			)
			(layer "F.SilkS")
		)
		(fp_rect
			(start -0.508 0.9398)
			(end 0.508 -0.9398)
			(stroke
				(width 0)
				(type default)
			)
			(fill no)
			(layer "F.CrtYd")
		)
		(fp_rect
			(start -0.508 0.9398)
			(end 0.508 -0.9398)
			(stroke
				(width 0)
				(type default)
			)
			(fill no)
			(layer "F.Fab")
		)
		(pad "1" smd custom
			(at 0 -0.4445 270)
			(size 0.1397 0.1397)
			(layers "F.Cu" "F.Mask" "F.Paste")
			(net "P3V3")
			(options
				(clearance outline)
				(anchor circle)
			)
			(primitives
				(gr_poly
					(pts
						(arc
							(start -0.1778 -0.2794)
							(mid -0.249642 -0.249642)
							(end -0.2794 -0.1778)
						)
						(arc
							(start -0.2794 0.1778)
							(mid -0.249642 0.249642)
							(end -0.1778 0.2794)
						)
						(arc
							(start 0.1778 0.2794)
							(mid 0.249642 0.249642)
							(end 0.2794 0.1778)
						)
						(arc
							(start 0.2794 -0.1778)
							(mid 0.249642 -0.249642)
							(end 0.1778 -0.2794)
						)
					)
					(width 0)
					(fill yes)
				)
			)
		)
		(pad "2" smd custom
			(at 0 0.4445 270)
			(size 0.1397 0.1397)
			(layers "F.Cu" "F.Mask" "F.Paste")
			(net "SSD4_CLK0_OE_N")
			(options
				(clearance outline)
				(anchor circle)
			)
			(primitives
				(gr_poly
					(pts
						(arc
							(start -0.1778 -0.2794)
							(mid -0.249642 -0.249642)
							(end -0.2794 -0.1778)
						)
						(arc
							(start -0.2794 0.1778)
							(mid -0.249642 0.249642)
							(end -0.1778 0.2794)
						)
						(arc
							(start 0.1778 0.2794)
							(mid 0.249642 0.249642)
							(end 0.2794 0.1778)
						)
						(arc
							(start 0.2794 -0.1778)
							(mid 0.249642 -0.249642)
							(end 0.1778 -0.2794)
						)
					)
					(width 0)
					(fill yes)
				)
			)
		)
	)
	(footprint ""
		(layer "F.Cu")
		(at 73.0504 -366.522)
		(property "Reference" "SR982"
			(at 0 0 0)
			(layer "F.SilkS")
			(hide yes)
			(effects
				(font
					(size 1.27 1.27)
				)
			)
		)
		(property "Value" "2KR2F-3-GP"
			(at 0.064008 -3.993896 0)
			(unlocked yes)
			(layer "F.Fab")
			(hide yes)
			(effects
				(font
					(size 1.016 1.016)
					(thickness 0.1524)
				)
			)
		)
		(property "Device Type" "R402H16"
			(at 0.064008 -5.517896 0)
			(unlocked yes)
			(layer "F.Fab")
			(hide yes)
			(effects
				(font
					(size 1.016 1.016)
					(thickness 0.1524)
				)
			)
		)
		(duplicate_pad_numbers_are_jumpers no)
		(fp_line
			(start -0.508 -0.9398)
			(end -0.508 0.9398)
			(stroke
				(width 0.1524)
				(type default)
			)
			(layer "F.SilkS")
		)
		(fp_line
			(start 0.508 -0.9398)
			(end -0.508 -0.9398)
			(stroke
				(width 0.1524)
				(type default)
			)
			(layer "F.SilkS")
		)
		(fp_rect
			(start -0.508 0.9398)
			(end 0.508 -0.9398)
			(stroke
				(width 0)
				(type default)
			)
			(fill no)
			(layer "F.CrtYd")
		)
		(fp_rect
			(start -0.508 0.9398)
			(end 0.508 -0.9398)
			(stroke
				(width 0)
				(type default)
			)
			(fill no)
			(layer "F.Fab")
		)
		(pad "1" smd custom
			(at 0 -0.4445)
			(size 0.1397 0.1397)
			(layers "F.Cu" "F.Mask" "F.Paste")
			(net "P3V3")
			(options
				(clearance outline)
				(anchor circle)
			)
			(primitives
				(gr_poly
					(pts
						(arc
							(start -0.1778 -0.2794)
							(mid -0.249642 -0.249642)
							(end -0.2794 -0.1778)
						)
						(arc
							(start -0.2794 0.1778)
							(mid -0.249642 0.249642)
							(end -0.1778 0.2794)
						)
						(arc
							(start 0.1778 0.2794)
							(mid 0.249642 0.249642)
							(end 0.2794 0.1778)
						)
						(arc
							(start 0.2794 -0.1778)
							(mid 0.249642 -0.249642)
							(end 0.1778 -0.2794)
						)
					)
					(width 0)
					(fill yes)
				)
			)
		)
		(pad "2" smd custom
			(at 0 0.4445)
			(size 0.1397 0.1397)
			(layers "F.Cu" "F.Mask" "F.Paste")
			(net "SDA_DR6")
			(options
				(clearance outline)
				(anchor circle)
			)
			(primitives
				(gr_poly
					(pts
						(arc
							(start -0.1778 -0.2794)
							(mid -0.249642 -0.249642)
							(end -0.2794 -0.1778)
						)
						(arc
							(start -0.2794 0.1778)
							(mid -0.249642 0.249642)
							(end -0.1778 0.2794)
						)
						(arc
							(start 0.1778 0.2794)
							(mid 0.249642 0.249642)
							(end 0.2794 0.1778)
						)
						(arc
							(start 0.2794 -0.1778)
							(mid 0.249642 -0.249642)
							(end 0.1778 -0.2794)
						)
					)
					(width 0)
					(fill yes)
				)
			)
		)
	)
	(footprint ""
		(layer "F.Cu")
		(at 20.3835 -60.88761 -90)
		(property "Reference" "SR1150"
			(at 0 0 270)
			(layer "F.SilkS")
			(hide yes)
			(effects
				(font
					(size 1.27 1.27)
				)
			)
		)
		(property "Value" "4K7R2J-2-GP"
			(at 0.064008 -3.993896 270)
			(unlocked yes)
			(layer "F.Fab")
			(hide yes)
			(effects
				(font
					(size 1.016 1.016)
					(thickness 0.1524)
				)
			)
		)
		(property "Device Type" "R402H16"
			(at 0.064008 -5.517896 270)
			(unlocked yes)
			(layer "F.Fab")
			(hide yes)
			(effects
				(font
					(size 1.016 1.016)
					(thickness 0.1524)
				)
			)
		)
		(duplicate_pad_numbers_are_jumpers no)
		(fp_line
			(start -0.508 -0.9398)
			(end -0.508 0.9398)
			(stroke
				(width 0.1524)
				(type default)
			)
			(layer "F.SilkS")
		)
		(fp_line
			(start 0.508 -0.9398)
			(end -0.508 -0.9398)
			(stroke
				(width 0.1524)
				(type default)
			)
			(layer "F.SilkS")
		)
		(fp_rect
			(start -0.508 0.9398)
			(end 0.508 -0.9398)
			(stroke
				(width 0)
				(type default)
			)
			(fill no)
			(layer "F.CrtYd")
		)
		(fp_rect
			(start -0.508 0.9398)
			(end 0.508 -0.9398)
			(stroke
				(width 0)
				(type default)
			)
			(fill no)
			(layer "F.Fab")
		)
		(pad "1" smd custom
			(at 0 -0.4445 270)
			(size 0.1397 0.1397)
			(layers "F.Cu" "F.Mask" "F.Paste")
			(net "P3V3")
			(options
				(clearance outline)
				(anchor circle)
			)
			(primitives
				(gr_poly
					(pts
						(arc
							(start -0.1778 -0.2794)
							(mid -0.249642 -0.249642)
							(end -0.2794 -0.1778)
						)
						(arc
							(start -0.2794 0.1778)
							(mid -0.249642 0.249642)
							(end -0.1778 0.2794)
						)
						(arc
							(start 0.1778 0.2794)
							(mid 0.249642 0.249642)
							(end 0.2794 0.1778)
						)
						(arc
							(start 0.2794 -0.1778)
							(mid 0.249642 -0.249642)
							(end 0.1778 -0.2794)
						)
					)
					(width 0)
					(fill yes)
				)
			)
		)
		(pad "2" smd custom
			(at 0 0.4445 270)
			(size 0.1397 0.1397)
			(layers "F.Cu" "F.Mask" "F.Paste")
			(net "SSD_ACT_DR14")
			(options
				(clearance outline)
				(anchor circle)
			)
			(primitives
				(gr_poly
					(pts
						(arc
							(start -0.1778 -0.2794)
							(mid -0.249642 -0.249642)
							(end -0.2794 -0.1778)
						)
						(arc
							(start -0.2794 0.1778)
							(mid -0.249642 0.249642)
							(end -0.1778 0.2794)
						)
						(arc
							(start 0.1778 0.2794)
							(mid 0.249642 0.249642)
							(end 0.2794 0.1778)
						)
						(arc
							(start 0.2794 -0.1778)
							(mid 0.249642 -0.249642)
							(end 0.1778 -0.2794)
						)
					)
					(width 0)
					(fill yes)
				)
			)
		)
	)
)
